# SCM (Grand Teton) — schematic netlist excerpt (pin names and nets, part order shuffled) for the footprints in the layout excerpt that follows; sources: Cadence DE-HDL packaged netlist, KiCad conversion of 12092022_DA0F0TMDCD0_F0T_Management_Board_D_brd_V3_OCP.brd

C73  Q_CAP  0.1UF 25V 10% X7R  pkg 0402  page 16 : A = P1V2_STBY_MVDD_CK ; B = GND
R130  Q_RES  22 1% CHIP  pkg 0402LF  page 12 : A = ESPI_LPC_D2_IO2 ; B = ESPI_LPC_LAD2_IO2

(kicad_pcb
	(version 20260206)
	(generator "pcbnew")
	(generator_version "10.0")
	(general
		(thickness 1.6)
		(legacy_teardrops no)
	)
	(paper "A4")
	(title_block
		(title "12092022_DA0F0TMDCD0_F0T_Management_Board_D_brd_V3_OCP.brd")
		(comment 1 "Grand Teton / footprints 767-768 of 1440")
	)
	(layers
		(0 "F.Cu" signal "TOP")
		(4 "In1.Cu" signal "GND")
		(6 "In2.Cu" signal "IN1")
		(8 "In3.Cu" signal "GND1")
		(10 "In4.Cu" signal "IN2")
		(12 "In5.Cu" signal "VCC")
		(14 "In6.Cu" signal "VCC1")
		(16 "In7.Cu" signal "IN3")
		(18 "In8.Cu" signal "GND2")
		(20 "In9.Cu" signal "IN4")
		(22 "In10.Cu" signal "GND3")
		(2 "B.Cu" signal "BOTTOM")
		(9 "F.Adhes" user "F.Adhesive")
		(11 "B.Adhes" user "B.Adhesive")
		(13 "F.Paste" user "Package Geometry/Pastemask Top")
		(15 "B.Paste" user "Package Geometry/Pastemask Bottom")
		(5 "F.SilkS" user "Ref Des/Silkscreen Top")
		(7 "B.SilkS" user "Ref Des/Silkscreen Bottom")
		(1 "F.Mask" user "Board Geometry/Soldermask Top")
		(3 "B.Mask" user "Board Geometry/Soldermask Bottom")
		(17 "Dwgs.User" user "User.Drawings")
		(19 "Cmts.User" user "User.Comments")
		(21 "Eco1.User" user "User.Eco1")
		(23 "Eco2.User" user "User.Eco2")
		(25 "Edge.Cuts" user "Board Geometry/Outline")
		(27 "Margin" user)
		(31 "F.CrtYd" user "Package Geometry/Place Bound Top")
		(29 "B.CrtYd" user "Package Geometry/Place Bound Bottom")
		(35 "F.Fab" user "Ref Des/Assembly Top")
		(33 "B.Fab" user "Ref Des/Assembly Bottom")
	)
	(footprint ""
		(layer "B.Cu")
		(at 63.129922 -49.472088 180)
		(property "Reference" "C73"
			(at 0 0 0)
			(layer "B.SilkS")
			(hide yes)
			(effects
				(font
					(size 1.27 1.27)
				)
				(justify mirror)
			)
		)
		(property "Value" ""
			(at 0 0 0)
			(layer "B.Fab")
			(effects
				(font
					(size 1.27 1.27)
				)
				(justify mirror)
			)
		)
		(duplicate_pad_numbers_are_jumpers no)
		(fp_line
			(start 0.7874 0.4064)
			(end 0.7874 -0.4064)
			(stroke
				(width 0.1524)
				(type default)
			)
			(layer "B.SilkS")
		)
		(fp_line
			(start 0.7874 -0.4064)
			(end -0.7874 -0.4064)
			(stroke
				(width 0.1524)
				(type default)
			)
			(layer "B.SilkS")
		)
		(fp_line
			(start -0.7874 0.4064)
			(end 0.7874 0.4064)
			(stroke
				(width 0.1524)
				(type default)
			)
			(layer "B.SilkS")
		)
		(fp_line
			(start -0.7874 -0.4064)
			(end -0.7874 0.4064)
			(stroke
				(width 0.1524)
				(type default)
			)
			(layer "B.SilkS")
		)
		(fp_line
			(start 0.67945 0.3048)
			(end 0.67945 -0.305054)
			(stroke
				(width 0.1)
				(type default)
			)
			(layer "B.Fab")
		)
		(fp_line
			(start 0.67945 -0.305054)
			(end 0.12065 -0.305054)
			(stroke
				(width 0.1)
				(type default)
			)
			(layer "B.Fab")
		)
		(fp_line
			(start 0.12065 0.3048)
			(end 0.67945 0.3048)
			(stroke
				(width 0.1)
				(type default)
			)
			(layer "B.Fab")
		)
		(fp_line
			(start 0.12065 0.2794)
			(end 0.12065 0.3048)
			(stroke
				(width 0.1)
				(type default)
			)
			(layer "B.Fab")
		)
		(fp_line
			(start 0.12065 -0.2794)
			(end -0.12065 -0.2794)
			(stroke
				(width 0.1)
				(type default)
			)
			(layer "B.Fab")
		)
		(fp_line
			(start 0.12065 -0.305054)
			(end 0.12065 -0.2794)
			(stroke
				(width 0.1)
				(type default)
			)
			(layer "B.Fab")
		)
		(fp_line
			(start -0.120396 0.3048)
			(end -0.120396 0.2794)
			(stroke
				(width 0.1)
				(type default)
			)
			(layer "B.Fab")
		)
		(fp_line
			(start -0.120396 0.2794)
			(end 0.12065 0.2794)
			(stroke
				(width 0.1)
				(type default)
			)
			(layer "B.Fab")
		)
		(fp_line
			(start -0.12065 -0.2794)
			(end -0.12065 -0.3048)
			(stroke
				(width 0.1)
				(type default)
			)
			(layer "B.Fab")
		)
		(fp_line
			(start -0.12065 -0.3048)
			(end -0.67945 -0.3048)
			(stroke
				(width 0.1)
				(type default)
			)
			(layer "B.Fab")
		)
		(fp_line
			(start -0.67945 0.3048)
			(end -0.120396 0.3048)
			(stroke
				(width 0.1)
				(type default)
			)
			(layer "B.Fab")
		)
		(fp_line
			(start -0.67945 -0.3048)
			(end -0.67945 0.3048)
			(stroke
				(width 0.1)
				(type default)
			)
			(layer "B.Fab")
		)
		(pad "1" smd circle
			(at 0.40005 0)
			(size 0 0)
			(layers "B.Cu" "B.Mask" "B.Paste")
			(net "P1V2_STBY_MVDD_CK")
		)
		(pad "2" smd circle
			(at -0.40005 0)
			(size 0 0)
			(layers "B.Cu" "B.Mask" "B.Paste")
			(net "GND")
		)
	)
	(footprint ""
		(layer "B.Cu")
		(at 60.556902 -61.858906 -90)
		(property "Reference" "R130"
			(at 0 0 90)
			(layer "B.SilkS")
			(hide yes)
			(effects
				(font
					(size 1.27 1.27)
				)
				(justify mirror)
			)
		)
		(property "Value" ""
			(at 0 0 90)
			(layer "B.Fab")
			(effects
				(font
					(size 1.27 1.27)
				)
				(justify mirror)
			)
		)
		(duplicate_pad_numbers_are_jumpers no)
		(fp_line
			(start -0.7874 0.4064)
			(end 0.7874 0.4064)
			(stroke
				(width 0.1524)
				(type default)
			)
			(layer "B.SilkS")
		)
		(fp_line
			(start 0.7874 0.4064)
			(end 0.7874 -0.4064)
			(stroke
				(width 0.1524)
				(type default)
			)
			(layer "B.SilkS")
		)
		(fp_line
			(start -0.7874 -0.4064)
			(end -0.7874 0.4064)
			(stroke
				(width 0.1524)
				(type default)
			)
			(layer "B.SilkS")
		)
		(fp_line
			(start 0.7874 -0.4064)
			(end -0.7874 -0.4064)
			(stroke
				(width 0.1524)
				(type default)
			)
			(layer "B.SilkS")
		)
		(fp_line
			(start -0.67945 0.3048)
			(end -0.120396 0.3048)
			(stroke
				(width 0.1)
				(type default)
			)
			(layer "B.Fab")
		)
		(fp_line
			(start -0.120396 0.3048)
			(end -0.120396 0.2794)
			(stroke
				(width 0.1)
				(type default)
			)
			(layer "B.Fab")
		)
		(fp_line
			(start 0.12065 0.3048)
			(end 0.67945 0.3048)
			(stroke
				(width 0.1)
				(type default)
			)
			(layer "B.Fab")
		)
		(fp_line
			(start 0.67945 0.3048)
			(end 0.67945 -0.305054)
			(stroke
				(width 0.1)
				(type default)
			)
			(layer "B.Fab")
		)
		(fp_line
			(start -0.120396 0.2794)
			(end 0.12065 0.2794)
			(stroke
				(width 0.1)
				(type default)
			)
			(layer "B.Fab")
		)
		(fp_line
			(start 0.12065 0.2794)
			(end 0.12065 0.3048)
			(stroke
				(width 0.1)
				(type default)
			)
			(layer "B.Fab")
		)
		(fp_line
			(start -0.12065 -0.2794)
			(end -0.12065 -0.3048)
			(stroke
				(width 0.1)
				(type default)
			)
			(layer "B.Fab")
		)
		(fp_line
			(start 0.12065 -0.2794)
			(end -0.12065 -0.2794)
			(stroke
				(width 0.1)
				(type default)
			)
			(layer "B.Fab")
		)
		(fp_line
			(start -0.67945 -0.3048)
			(end -0.67945 0.3048)
			(stroke
				(width 0.1)
				(type default)
			)
			(layer "B.Fab")
		)
		(fp_line
			(start -0.12065 -0.3048)
			(end -0.67945 -0.3048)
			(stroke
				(width 0.1)
				(type default)
			)
			(layer "B.Fab")
		)
		(fp_line
			(start 0.12065 -0.305054)
			(end 0.12065 -0.2794)
			(stroke
				(width 0.1)
				(type default)
			)
			(layer "B.Fab")
		)
		(fp_line
			(start 0.67945 -0.305054)
			(end 0.12065 -0.305054)
			(stroke
				(width 0.1)
				(type default)
			)
			(layer "B.Fab")
		)
		(pad "1" smd circle
			(at 0.40005 0 90)
			(size 0 0)
			(layers "B.Cu" "B.Mask" "B.Paste")
			(net "ESPI_LPC_D2_IO2")
		)
		(pad "2" smd circle
			(at -0.40005 0 90)
			(size 0 0)
			(layers "B.Cu" "B.Mask" "B.Paste")
			(net "ESPI_LPC_LAD2_IO2")
		)
	)
)
